# BASEBOARD_FAB2 (Tioga Pass) — schematic netlist excerpt (pin names and nets, part order shuffled) for the footprints in the layout excerpt that follows; sources: Cadence DE-HDL packaged netlist, KiCad conversion of Wiwynn_Tioga_Pass_MB.brd

C8T1  CAP_A  47UF 4V 20% X5R  pkg 0603V  page 225 : A = PVDDQ_GHJ ; B = GND
R7E7  RES  4.75K 1% CHIP  pkg 0402  page 95 : A = P3V3 ; B = FM_SYS_THROTTLE_LVC3
C7D2  CAP  10UF 6.3V 20% X6S  pkg 0603  page 130 : A = P3V3_STBY ; B = GND

(kicad_pcb
	(version 20260206)
	(generator "pcbnew")
	(generator_version "10.0")
	(general
		(thickness 1.6)
		(legacy_teardrops no)
	)
	(paper "A4")
	(title_block
		(title "Wiwynn_Tioga_Pass_MB.brd")
		(comment 1 "Tioga Pass / footprints 2647-2649 of 4770")
	)
	(layers
		(0 "F.Cu" signal "TOP")
		(4 "In1.Cu" signal "L2GND")
		(6 "In2.Cu" signal "L3")
		(8 "In3.Cu" signal "L4GND")
		(10 "In4.Cu" signal "L5")
		(12 "In5.Cu" signal "L6GND")
		(14 "In6.Cu" signal "L7VCC")
		(16 "In7.Cu" signal "L8VCC")
		(18 "In8.Cu" signal "L9GND")
		(20 "In9.Cu" signal "L10")
		(22 "In10.Cu" signal "L11GND")
		(24 "In11.Cu" signal "L12")
		(26 "In12.Cu" signal "L13GND")
		(2 "B.Cu" signal "BOTTOM")
		(9 "F.Adhes" user "F.Adhesive")
		(11 "B.Adhes" user "B.Adhesive")
		(13 "F.Paste" user "Package Geometry/Pastemask Top")
		(15 "B.Paste" user "Package Geometry/Pastemask Bottom")
		(5 "F.SilkS" user "Ref Des/Silkscreen Top")
		(7 "B.SilkS" user "Ref Des/Silkscreen Bottom")
		(1 "F.Mask" user "Board Geometry/Soldermask Top")
		(3 "B.Mask" user "Board Geometry/Soldermask Bottom")
		(17 "Dwgs.User" user "User.Drawings")
		(19 "Cmts.User" user "User.Comments")
		(21 "Eco1.User" user "User.Eco1")
		(23 "Eco2.User" user "User.Eco2")
		(25 "Edge.Cuts" user "Board Geometry/Outline")
		(27 "Margin" user)
		(31 "F.CrtYd" user "Package Geometry/Place Bound Top")
		(29 "B.CrtYd" user "Package Geometry/Place Bound Bottom")
		(35 "F.Fab" user "Ref Des/Assembly Top")
		(33 "B.Fab" user "Ref Des/Assembly Bottom")
	)
	(footprint ""
		(layer "B.Cu")
		(at 400.1262 -102.8319)
		(property "Reference" "C7D2"
			(at 0 0 0)
			(layer "B.SilkS")
			(hide yes)
			(effects
				(font
					(size 1.27 1.27)
				)
				(justify mirror)
			)
		)
		(property "Value" ""
			(at 0 0 0)
			(layer "B.Fab")
			(effects
				(font
					(size 1.27 1.27)
				)
				(justify mirror)
			)
		)
		(duplicate_pad_numbers_are_jumpers no)
		(fp_poly
			(pts
				(xy 0.4953 -0.2032) (xy -0.4953 -0.2032) (xy -0.4953 1.6002) (xy 0.4953 1.6002)
			)
			(stroke
				(width 0)
				(type default)
			)
			(fill no)
			(layer "B.CrtYd")
		)
		(fp_line
			(start -0.4953 -0.2032)
			(end -0.4953 1.6002)
			(stroke
				(width 0.1)
				(type default)
			)
			(layer "B.Fab")
		)
		(fp_line
			(start -0.4953 1.6002)
			(end 0.4953 1.6002)
			(stroke
				(width 0.1)
				(type default)
			)
			(layer "B.Fab")
		)
		(fp_line
			(start 0.4953 -0.2032)
			(end -0.4953 -0.2032)
			(stroke
				(width 0.1)
				(type default)
			)
			(layer "B.Fab")
		)
		(fp_line
			(start 0.4953 1.6002)
			(end 0.4953 -0.2032)
			(stroke
				(width 0.1)
				(type default)
			)
			(layer "B.Fab")
		)
		(pad "1" smd rect
			(at 0 0 180)
			(size 0.762 0.889)
			(layers "B.Cu" "B.Mask" "B.Paste")
			(net "P3V3_STBY")
		)
		(pad "2" smd rect
			(at 0 1.397 180)
			(size 0.762 0.889)
			(layers "B.Cu" "B.Mask" "B.Paste")
			(net "GND")
		)
		(zone
			(layer "B.Cu")
			(hatch none 0.5)
			(connect_pads
				(clearance 0)
			)
			(min_thickness 0.25)
			(keepout
				(tracks not_allowed)
				(vias allowed)
				(pads allowed)
				(copperpour not_allowed)
				(footprints allowed)
			)
			(placement
				(enabled no)
				(sheetname "")
			)
			(fill
				(thermal_gap 0.5)
				(thermal_bridge_width 0.5)
				(island_removal_mode 0)
			)
			(polygon
				(pts
					(xy 400.5072 -102.3874) (xy 399.7452 -102.3874) (xy 399.7452 -101.8794) (xy 400.5072 -101.8794)
				)
			)
		)
	)
	(footprint ""
		(layer "B.Cu")
		(at 382.3335 -44.196 90)
		(property "Reference" "R7E7"
			(at 0 0 90)
			(layer "B.SilkS")
			(hide yes)
			(effects
				(font
					(size 1.27 1.27)
				)
				(justify mirror)
			)
		)
		(property "Value" ""
			(at 0 0 90)
			(layer "B.Fab")
			(effects
				(font
					(size 1.27 1.27)
				)
				(justify mirror)
			)
		)
		(duplicate_pad_numbers_are_jumpers no)
		(fp_poly
			(pts
				(xy 0.2794 -0.1016) (xy -0.2794 -0.1016) (xy -0.2794 0.9906) (xy 0.2794 0.9906)
			)
			(stroke
				(width 0)
				(type default)
			)
			(fill no)
			(layer "B.CrtYd")
		)
		(fp_line
			(start 0.2794 -0.1016)
			(end 0.2794 0.9906)
			(stroke
				(width 0.1)
				(type default)
			)
			(layer "B.Fab")
		)
		(fp_line
			(start -0.2794 -0.1016)
			(end 0.2794 -0.1016)
			(stroke
				(width 0.1)
				(type default)
			)
			(layer "B.Fab")
		)
		(fp_line
			(start 0.2794 0.9906)
			(end -0.2794 0.9906)
			(stroke
				(width 0.1)
				(type default)
			)
			(layer "B.Fab")
		)
		(fp_line
			(start -0.2794 0.9906)
			(end -0.2794 -0.1016)
			(stroke
				(width 0.1)
				(type default)
			)
			(layer "B.Fab")
		)
		(pad "1" smd rect
			(at 0 0 270)
			(size 0.508 0.508)
			(layers "B.Cu" "B.Mask" "B.Paste")
			(net "P3V3")
		)
		(pad "2" smd rect
			(at 0 0.889 270)
			(size 0.508 0.508)
			(layers "B.Cu" "B.Mask" "B.Paste")
			(net "FM_SYS_THROTTLE_LVC3")
		)
		(zone
			(layer "B.Cu")
			(hatch none 0.5)
			(connect_pads
				(clearance 0)
			)
			(min_thickness 0.25)
			(keepout
				(tracks allowed)
				(vias not_allowed)
				(pads allowed)
				(copperpour not_allowed)
				(footprints allowed)
			)
			(placement
				(enabled no)
				(sheetname "")
			)
			(fill
				(thermal_gap 0.5)
				(thermal_bridge_width 0.5)
				(island_removal_mode 0)
			)
			(polygon
				(pts
					(xy 382.5875 -44.45) (xy 382.5875 -43.942) (xy 382.9685 -43.942) (xy 382.9685 -44.45)
				)
			)
		)
		(zone
			(layer "B.Cu")
			(hatch none 0.5)
			(connect_pads
				(clearance 0)
			)
			(min_thickness 0.25)
			(keepout
				(tracks not_allowed)
				(vias allowed)
				(pads allowed)
				(copperpour not_allowed)
				(footprints allowed)
			)
			(placement
				(enabled no)
				(sheetname "")
			)
			(fill
				(thermal_gap 0.5)
				(thermal_bridge_width 0.5)
				(island_removal_mode 0)
			)
			(polygon
				(pts
					(xy 382.9685 -44.45) (xy 382.9685 -43.942) (xy 382.5875 -43.942) (xy 382.5875 -44.45)
				)
			)
		)
	)
	(footprint ""
		(layer "B.Cu")
		(at 79.499968 -27.813 -90)
		(property "Reference" "C8T1"
			(at 0 0 90)
			(layer "B.SilkS")
			(hide yes)
			(effects
				(font
					(size 1.27 1.27)
				)
				(justify mirror)
			)
		)
		(property "Value" ""
			(at 0 0 90)
			(layer "B.Fab")
			(effects
				(font
					(size 1.27 1.27)
				)
				(justify mirror)
			)
		)
		(duplicate_pad_numbers_are_jumpers no)
		(fp_rect
			(start 0.500126 1.598422)
			(end -0.500126 -0.201422)
			(stroke
				(width 0)
				(type default)
			)
			(fill no)
			(layer "B.CrtYd")
		)
		(fp_line
			(start -0.500126 1.598422)
			(end 0.500126 1.598422)
			(stroke
				(width 0.1)
				(type default)
			)
			(layer "B.Fab")
		)
		(fp_line
			(start 0.500126 1.598422)
			(end 0.500126 -0.201422)
			(stroke
				(width 0.1)
				(type default)
			)
			(layer "B.Fab")
		)
		(fp_line
			(start -0.500126 -0.201422)
			(end -0.500126 1.598422)
			(stroke
				(width 0.1)
				(type default)
			)
			(layer "B.Fab")
		)
		(fp_line
			(start 0.500126 -0.201422)
			(end -0.500126 -0.201422)
			(stroke
				(width 0.1)
				(type default)
			)
			(layer "B.Fab")
		)
		(pad "1" smd rect
			(at 0 0 180)
			(size 0.889 0.9906)
			(layers "B.Cu" "B.Mask" "B.Paste")
			(net "PVDDQ_GHJ")
		)
		(pad "2" smd rect
			(at 0 1.397 180)
			(size 0.889 0.9906)
			(layers "B.Cu" "B.Mask" "B.Paste")
			(net "GND")
		)
		(zone
			(layer "B.Cu")
			(hatch none 0.5)
			(connect_pads
				(clearance 0)
			)
			(min_thickness 0.25)
			(keepout
				(tracks allowed)
				(vias not_allowed)
				(pads allowed)
				(copperpour not_allowed)
				(footprints allowed)
			)
			(placement
				(enabled no)
				(sheetname "")
			)
			(fill
				(thermal_gap 0.5)
				(thermal_bridge_width 0.5)
				(island_removal_mode 0)
			)
			(polygon
				(pts
					(xy 78.547468 -27.3177) (xy 79.055468 -27.3177) (xy 79.055468 -28.3083) (xy 78.547468 -28.3083)
				)
			)
		)
		(zone
			(layer "B.Cu")
			(hatch none 0.5)
			(connect_pads
				(clearance 0)
			)
			(min_thickness 0.25)
			(keepout
				(tracks not_allowed)
				(vias allowed)
				(pads allowed)
				(copperpour not_allowed)
				(footprints allowed)
			)
			(placement
				(enabled no)
				(sheetname "")
			)
			(fill
				(thermal_gap 0.5)
				(thermal_bridge_width 0.5)
				(island_removal_mode 0)
			)
			(polygon
				(pts
					(xy 78.547468 -27.3177) (xy 79.055468 -27.3177) (xy 79.055468 -28.3083) (xy 78.547468 -28.3083)
				)
			)
		)
	)
)
